(kicad_pcb
	(version 20260206)
	(generator "pcbnew")
	(generator_version "10.0")
	(general
		(thickness 1.6)
		(legacy_teardrops no)
	)
	(paper "A4")
	(title_block
		(title "Bryce Canyon_R.DPB_16317-1_OCP.brd")
		(comment 1 "Bryce Canyon / footprints 1057-1064 of 2099")
	)
	(layers
		(0 "F.Cu" signal "TOP")
		(4 "In1.Cu" signal "L2GND")
		(6 "In2.Cu" signal "L3")
		(8 "In3.Cu" signal "L4VCC")
		(10 "In4.Cu" signal "L5VCC")
		(12 "In5.Cu" signal "L6")
		(14 "In6.Cu" signal "L7GND")
		(2 "B.Cu" signal "BOTTOM")
		(9 "F.Adhes" user "F.Adhesive")
		(11 "B.Adhes" user "B.Adhesive")
		(13 "F.Paste" user "Package Geometry/Pastemask Top")
		(15 "B.Paste" user "Package Geometry/Pastemask Bottom")
		(5 "F.SilkS" user "Ref Des/Silkscreen Top")
		(7 "B.SilkS" user "Ref Des/Silkscreen Bottom")
		(1 "F.Mask" user "Board Geometry/Soldermask Top")
		(3 "B.Mask" user "Board Geometry/Soldermask Bottom")
		(17 "Dwgs.User" user "User.Drawings")
		(19 "Cmts.User" user "User.Comments")
		(21 "Eco1.User" user "User.Eco1")
		(23 "Eco2.User" user "User.Eco2")
		(25 "Edge.Cuts" user "Board Geometry/Outline")
		(27 "Margin" user)
		(31 "F.CrtYd" user "Package Geometry/Place Bound Top")
		(29 "B.CrtYd" user "Package Geometry/Place Bound Bottom")
		(35 "F.Fab" user "Ref Des/Assembly Top")
		(33 "B.Fab" user "Ref Des/Assembly Bottom")
	)
	(footprint ""
		(layer "F.Cu")
		(at 477.152462 -244.884194 90)
		(property "Reference" "VIA23"
			(at 0 0 90)
			(layer "F.SilkS")
			(hide yes)
			(effects
				(font
					(size 1.27 1.27)
				)
			)
		)
		(property "Value" "100OHM-8L-2D36MM-L18-GP"
			(at 3.8989 0.5715 90)
			(unlocked yes)
			(layer "F.Fab")
			(hide yes)
			(effects
				(font
					(size 1.016 1.016)
					(thickness 0.1524)
				)
			)
		)
		(property "Device Type" "VIA-PCIE-4P-414097"
			(at 3.8989 -0.9525 90)
			(unlocked yes)
			(layer "F.Fab")
			(hide yes)
			(effects
				(font
					(size 1.016 1.016)
					(thickness 0.1524)
				)
			)
		)
		(duplicate_pad_numbers_are_jumpers no)
		(fp_rect
			(start -2.0701 0.4826)
			(end 2.0701 -0.4826)
			(stroke
				(width 0)
				(type default)
			)
			(fill no)
			(layer "F.CrtYd")
		)
		(fp_rect
			(start -2.0701 0.4826)
			(end 2.0701 -0.4826)
			(stroke
				(width 0)
				(type default)
			)
			(fill no)
			(layer "F.Fab")
		)
		(pad "1" thru_hole circle
			(at -1.5875 0 90)
			(size 0.508 0.508)
			(drill 0.254)
			(layers "*.Cu" "*.Mask")
			(remove_unused_layers no)
			(net "GND")
			(clearance 0.2286)
			(thermal_gap 0.2286)
		)
		(pad "2" thru_hole circle
			(at -0.5715 0 90)
			(size 0.508 0.508)
			(drill 0.254)
			(layers "*.Cu" "*.Mask")
			(remove_unused_layers no)
			(net "PHY_SCC_B_TO_DRV_B_11_DP")
			(clearance 0.2286)
			(thermal_gap 0.2286)
		)
		(pad "3" thru_hole circle
			(at 0.5715 0 90)
			(size 0.508 0.508)
			(drill 0.254)
			(layers "*.Cu" "*.Mask")
			(remove_unused_layers no)
			(net "PHY_SCC_B_TO_DRV_B_11_DN")
			(clearance 0.2286)
			(thermal_gap 0.2286)
		)
		(pad "4" thru_hole circle
			(at 1.5875 0 90)
			(size 0.508 0.508)
			(drill 0.254)
			(layers "*.Cu" "*.Mask")
			(remove_unused_layers no)
			(net "GND")
			(clearance 0.2286)
			(thermal_gap 0.2286)
		)
	)
	(footprint ""
		(layer "F.Cu")
		(at 141.478 -248.158 180)
		(property "Reference" "R234"
			(at 0 0 180)
			(layer "F.SilkS")
			(hide yes)
			(effects
				(font
					(size 1.27 1.27)
				)
			)
		)
		(property "Value" "200KR2F-L-GP"
			(at 0.064008 -3.993896 180)
			(unlocked yes)
			(layer "F.Fab")
			(hide yes)
			(effects
				(font
					(size 1.016 1.016)
					(thickness 0.1524)
				)
			)
		)
		(property "Device Type" "R402H16"
			(at 0.064008 -5.517896 180)
			(unlocked yes)
			(layer "F.Fab")
			(hide yes)
			(effects
				(font
					(size 1.016 1.016)
					(thickness 0.1524)
				)
			)
		)
		(duplicate_pad_numbers_are_jumpers no)
		(fp_line
			(start 0.508 -0.9398)
			(end -0.508 -0.9398)
			(stroke
				(width 0.1524)
				(type default)
			)
			(layer "F.SilkS")
		)
		(fp_line
			(start -0.508 -0.9398)
			(end -0.508 0.9398)
			(stroke
				(width 0.1524)
				(type default)
			)
			(layer "F.SilkS")
		)
		(fp_rect
			(start -0.508 0.9398)
			(end 0.508 -0.9398)
			(stroke
				(width 0)
				(type default)
			)
			(fill no)
			(layer "F.CrtYd")
		)
		(fp_rect
			(start -0.508 0.9398)
			(end 0.508 -0.9398)
			(stroke
				(width 0)
				(type default)
			)
			(fill no)
			(layer "F.Fab")
		)
		(pad "1" smd custom
			(at 0 -0.4445 180)
			(size 0.1397 0.1397)
			(layers "F.Cu" "F.Mask" "F.Paste")
			(net "SW_HDD_R4")
			(options
				(clearance outline)
				(anchor circle)
			)
			(primitives
				(gr_poly
					(pts
						(arc
							(start -0.1778 -0.2794)
							(mid -0.249642 -0.249642)
							(end -0.2794 -0.1778)
						)
						(arc
							(start -0.2794 0.1778)
							(mid -0.249642 0.249642)
							(end -0.1778 0.2794)
						)
						(arc
							(start 0.1778 0.2794)
							(mid 0.249642 0.249642)
							(end 0.2794 0.1778)
						)
						(arc
							(start 0.2794 -0.1778)
							(mid 0.249642 -0.249642)
							(end 0.1778 -0.2794)
						)
					)
					(width 0)
					(fill yes)
				)
			)
		)
		(pad "2" smd custom
			(at 0 0.4445 180)
			(size 0.1397 0.1397)
			(layers "F.Cu" "F.Mask" "F.Paste")
			(net "SW_HDD_N4")
			(options
				(clearance outline)
				(anchor circle)
			)
			(primitives
				(gr_poly
					(pts
						(arc
							(start -0.1778 -0.2794)
							(mid -0.249642 -0.249642)
							(end -0.2794 -0.1778)
						)
						(arc
							(start -0.2794 0.1778)
							(mid -0.249642 0.249642)
							(end -0.1778 0.2794)
						)
						(arc
							(start 0.1778 0.2794)
							(mid 0.249642 0.249642)
							(end 0.2794 0.1778)
						)
						(arc
							(start 0.2794 -0.1778)
							(mid 0.249642 -0.249642)
							(end 0.1778 -0.2794)
						)
					)
					(width 0)
					(fill yes)
				)
			)
		)
	)
	(footprint ""
		(layer "F.Cu")
		(at 146.304 -32.004 -90)
		(property "Reference" "C395"
			(at 0 0 270)
			(layer "F.SilkS")
			(hide yes)
			(effects
				(font
					(size 1.27 1.27)
				)
			)
		)
		(property "Value" "SC10U16V6KX-2GP"
			(at -0.0762 -5.1308 270)
			(unlocked yes)
			(layer "F.Fab")
			(hide yes)
			(effects
				(font
					(size 1.016 1.016)
					(thickness 0.1524)
				)
			)
		)
		(property "Device Type" "C1206H71"
			(at -0.127 -6.6548 270)
			(unlocked yes)
			(layer "F.Fab")
			(hide yes)
			(effects
				(font
					(size 1.016 1.016)
					(thickness 0.1524)
				)
			)
		)
		(duplicate_pad_numbers_are_jumpers no)
		(fp_line
			(start -1.016 2.2352)
			(end -1.016 0.8382)
			(stroke
				(width 0.1524)
				(type default)
			)
			(layer "F.SilkS")
		)
		(fp_line
			(start 1.016 2.2352)
			(end -1.016 2.2352)
			(stroke
				(width 0.1524)
				(type default)
			)
			(layer "F.SilkS")
		)
		(fp_line
			(start 1.016 0.8382)
			(end 1.016 2.2352)
			(stroke
				(width 0.1524)
				(type default)
			)
			(layer "F.SilkS")
		)
		(fp_line
			(start -1.016 -0.8382)
			(end -1.016 -2.2352)
			(stroke
				(width 0.1524)
				(type default)
			)
			(layer "F.SilkS")
		)
		(fp_line
			(start -1.016 -2.2352)
			(end 1.016 -2.2352)
			(stroke
				(width 0.1524)
				(type default)
			)
			(layer "F.SilkS")
		)
		(fp_line
			(start 1.016 -2.2352)
			(end 1.016 -0.8382)
			(stroke
				(width 0.1524)
				(type default)
			)
			(layer "F.SilkS")
		)
		(fp_rect
			(start -1.0922 2.3114)
			(end 1.0922 -2.3114)
			(stroke
				(width 0)
				(type default)
			)
			(fill no)
			(layer "F.CrtYd")
		)
		(fp_poly
			(pts
				(xy 1.0922 -2.3114) (xy 1.0922 2.3114) (xy -1.0922 2.3114) (xy -1.0922 -2.3114)
			)
			(stroke
				(width 0)
				(type default)
			)
			(fill no)
			(layer "F.Fab")
		)
		(pad "1" smd rect
			(at 0 -1.397 270)
			(size 1.651 1.27)
			(layers "F.Cu" "F.Mask" "F.Paste")
			(net "P5V_HDD28")
		)
		(pad "2" smd rect
			(at 0 1.397 270)
			(size 1.651 1.27)
			(layers "F.Cu" "F.Mask" "F.Paste")
			(net "GND")
		)
	)
	(footprint ""
		(layer "F.Cu")
		(at 462.159604 -373.6086 90)
		(property "Reference" "R1300"
			(at 0 0 90)
			(layer "F.SilkS")
			(hide yes)
			(effects
				(font
					(size 1.27 1.27)
				)
			)
		)
		(property "Value" "4K7R2F-GP"
			(at 0.064008 -3.993896 90)
			(unlocked yes)
			(layer "F.Fab")
			(hide yes)
			(effects
				(font
					(size 1.016 1.016)
					(thickness 0.1524)
				)
			)
		)
		(property "Device Type" "R402H16"
			(at 0.064008 -5.517896 90)
			(unlocked yes)
			(layer "F.Fab")
			(hide yes)
			(effects
				(font
					(size 1.016 1.016)
					(thickness 0.1524)
				)
			)
		)
		(duplicate_pad_numbers_are_jumpers no)
		(fp_line
			(start 0.508 -0.9398)
			(end -0.508 -0.9398)
			(stroke
				(width 0.1524)
				(type default)
			)
			(layer "F.SilkS")
		)
		(fp_line
			(start -0.508 -0.9398)
			(end -0.508 0.9398)
			(stroke
				(width 0.1524)
				(type default)
			)
			(layer "F.SilkS")
		)
		(fp_rect
			(start -0.508 0.9398)
			(end 0.508 -0.9398)
			(stroke
				(width 0)
				(type default)
			)
			(fill no)
			(layer "F.CrtYd")
		)
		(fp_rect
			(start -0.508 0.9398)
			(end 0.508 -0.9398)
			(stroke
				(width 0)
				(type default)
			)
			(fill no)
			(layer "F.Fab")
		)
		(pad "1" smd custom
			(at 0 -0.4445 90)
			(size 0.1397 0.1397)
			(layers "F.Cu" "F.Mask" "F.Paste")
			(net "FAN_YELLOW_LED3")
			(options
				(clearance outline)
				(anchor circle)
			)
			(primitives
				(gr_poly
					(pts
						(arc
							(start -0.1778 -0.2794)
							(mid -0.249642 -0.249642)
							(end -0.2794 -0.1778)
						)
						(arc
							(start -0.2794 0.1778)
							(mid -0.249642 0.249642)
							(end -0.1778 0.2794)
						)
						(arc
							(start 0.1778 0.2794)
							(mid 0.249642 0.249642)
							(end 0.2794 0.1778)
						)
						(arc
							(start 0.2794 -0.1778)
							(mid 0.249642 -0.249642)
							(end 0.1778 -0.2794)
						)
					)
					(width 0)
					(fill yes)
				)
			)
		)
		(pad "2" smd custom
			(at 0 0.4445 90)
			(size 0.1397 0.1397)
			(layers "F.Cu" "F.Mask" "F.Paste")
			(net "P12V_IN")
			(options
				(clearance outline)
				(anchor circle)
			)
			(primitives
				(gr_poly
					(pts
						(arc
							(start -0.1778 -0.2794)
							(mid -0.249642 -0.249642)
							(end -0.2794 -0.1778)
						)
						(arc
							(start -0.2794 0.1778)
							(mid -0.249642 0.249642)
							(end -0.1778 0.2794)
						)
						(arc
							(start 0.1778 0.2794)
							(mid 0.249642 0.249642)
							(end 0.2794 0.1778)
						)
						(arc
							(start 0.2794 -0.1778)
							(mid 0.249642 -0.249642)
							(end 0.1778 -0.2794)
						)
					)
					(width 0)
					(fill yes)
				)
			)
		)
	)
	(footprint ""
		(layer "F.Cu")
		(at 394.6398 -135.5852 -90)
		(property "Reference" "C298"
			(at 0 0 270)
			(layer "F.SilkS")
			(hide yes)
			(effects
				(font
					(size 1.27 1.27)
				)
			)
		)
		(property "Value" "SCD033U25V2KX-GP"
			(at 1.1811 -2.7051 270)
			(unlocked yes)
			(layer "F.Fab")
			(hide yes)
			(effects
				(font
					(size 1.016 1.016)
					(thickness 0.1524)
				)
			)
		)
		(property "Device Type" "C402H22"
			(at 1.1811 -4.2291 270)
			(unlocked yes)
			(layer "F.Fab")
			(hide yes)
			(effects
				(font
					(size 1.016 1.016)
					(thickness 0.1524)
				)
			)
		)
		(duplicate_pad_numbers_are_jumpers no)
		(fp_rect
			(start -0.4318 0.9525)
			(end 0.4318 -0.9525)
			(stroke
				(width 0)
				(type default)
			)
			(fill no)
			(layer "F.CrtYd")
		)
		(fp_rect
			(start -0.4318 0.9525)
			(end 0.4318 -0.9525)
			(stroke
				(width 0)
				(type default)
			)
			(fill no)
			(layer "F.Fab")
		)
		(pad "1" smd custom
			(at 0 -0.4445 270)
			(size 0.1524 0.1524)
			(layers "F.Cu" "F.Mask" "F.Paste")
			(net "SW_HDD_P20")
			(options
				(clearance outline)
				(anchor circle)
			)
			(primitives
				(gr_poly
					(pts
						(arc
							(start 0.3048 -0.2032)
							(mid 0.275042 -0.275042)
							(end 0.2032 -0.3048)
						)
						(arc
							(start -0.2032 -0.3048)
							(mid -0.275042 -0.275042)
							(end -0.3048 -0.2032)
						)
						(arc
							(start -0.3048 0.2032)
							(mid -0.275042 0.275042)
							(end -0.2032 0.3048)
						)
						(arc
							(start 0.2032 0.3048)
							(mid 0.275042 0.275042)
							(end 0.3048 0.2032)
						)
					)
					(width 0)
					(fill yes)
				)
			)
		)
		(pad "2" smd custom
			(at 0 0.4445 270)
			(size 0.1524 0.1524)
			(layers "F.Cu" "F.Mask" "F.Paste")
			(net "GND")
			(options
				(clearance outline)
				(anchor circle)
			)
			(primitives
				(gr_poly
					(pts
						(arc
							(start 0.3048 -0.2032)
							(mid 0.275042 -0.275042)
							(end 0.2032 -0.3048)
						)
						(arc
							(start -0.2032 -0.3048)
							(mid -0.275042 -0.275042)
							(end -0.3048 -0.2032)
						)
						(arc
							(start -0.3048 0.2032)
							(mid -0.275042 0.275042)
							(end -0.2032 0.3048)
						)
						(arc
							(start 0.2032 0.3048)
							(mid 0.275042 0.275042)
							(end 0.3048 0.2032)
						)
					)
					(width 0)
					(fill yes)
				)
			)
		)
	)
	(footprint ""
		(layer "F.Cu")
		(at 130.302 -266.065 90)
		(property "Reference" "R209"
			(at 0 0 90)
			(layer "F.SilkS")
			(hide yes)
			(effects
				(font
					(size 1.27 1.27)
				)
			)
		)
		(property "Value" "220R3F-1-GP"
			(at -0.0254 -2.5146 90)
			(unlocked yes)
			(layer "F.Fab")
			(hide yes)
			(effects
				(font
					(size 1.016 1.016)
					(thickness 0.1524)
				)
			)
		)
		(property "Device Type" "R603H22"
			(at -0.0254 -4.0386 90)
			(unlocked yes)
			(layer "F.Fab")
			(hide yes)
			(effects
				(font
					(size 1.016 1.016)
					(thickness 0.1524)
				)
			)
		)
		(duplicate_pad_numbers_are_jumpers no)
		(fp_line
			(start 0.2032 0)
			(end 0.4826 0)
			(stroke
				(width 0.2032)
				(type default)
			)
			(layer "F.SilkS")
		)
		(fp_line
			(start -0.4826 0)
			(end -0.2032 0)
			(stroke
				(width 0.2032)
				(type default)
			)
			(layer "F.SilkS")
		)
		(fp_rect
			(start -0.5842 1.3335)
			(end 0.5842 -1.3335)
			(stroke
				(width 0)
				(type default)
			)
			(fill no)
			(layer "F.CrtYd")
		)
		(fp_rect
			(start -0.5842 1.3335)
			(end 0.5842 -1.3335)
			(stroke
				(width 0)
				(type default)
			)
			(fill no)
			(layer "F.Fab")
		)
		(pad "1" smd custom
			(at 0 -0.762 90)
			(size 0.2159 0.2159)
			(layers "F.Cu" "F.Mask" "F.Paste")
			(net "HDD_PRSNT_3")
			(options
				(clearance outline)
				(anchor circle)
			)
			(primitives
				(gr_poly
					(pts
						(arc
							(start -0.3302 -0.4318)
							(mid -0.402042 -0.402042)
							(end -0.4318 -0.3302)
						)
						(arc
							(start -0.4318 0.3302)
							(mid -0.402042 0.402042)
							(end -0.3302 0.4318)
						)
						(arc
							(start 0.3302 0.4318)
							(mid 0.402042 0.402042)
							(end 0.4318 0.3302)
						)
						(arc
							(start 0.4318 -0.3302)
							(mid 0.402042 -0.402042)
							(end 0.3302 -0.4318)
						)
					)
					(width 0)
					(fill yes)
				)
			)
		)
		(pad "2" smd custom
			(at 0 0.762 90)
			(size 0.2159 0.2159)
			(layers "F.Cu" "F.Mask" "F.Paste")
			(net "DRIVE_B_3_INS")
			(options
				(clearance outline)
				(anchor circle)
			)
			(primitives
				(gr_poly
					(pts
						(arc
							(start -0.3302 -0.4318)
							(mid -0.402042 -0.402042)
							(end -0.4318 -0.3302)
						)
						(arc
							(start -0.4318 0.3302)
							(mid -0.402042 0.402042)
							(end -0.3302 0.4318)
						)
						(arc
							(start 0.3302 0.4318)
							(mid 0.402042 0.402042)
							(end 0.4318 0.3302)
						)
						(arc
							(start 0.4318 -0.3302)
							(mid 0.402042 -0.402042)
							(end 0.3302 -0.4318)
						)
					)
					(width 0)
					(fill yes)
				)
			)
		)
	)
	(footprint ""
		(layer "F.Cu")
		(at 141.478 -18.161 180)
		(property "Reference" "R730"
			(at 0 0 180)
			(layer "F.SilkS")
			(hide yes)
			(effects
				(font
					(size 1.27 1.27)
				)
			)
		)
		(property "Value" "200KR2F-L-GP"
			(at 0.064008 -3.993896 180)
			(unlocked yes)
			(layer "F.Fab")
			(hide yes)
			(effects
				(font
					(size 1.016 1.016)
					(thickness 0.1524)
				)
			)
		)
		(property "Device Type" "R402H16"
			(at 0.064008 -5.517896 180)
			(unlocked yes)
			(layer "F.Fab")
			(hide yes)
			(effects
				(font
					(size 1.016 1.016)
					(thickness 0.1524)
				)
			)
		)
		(duplicate_pad_numbers_are_jumpers no)
		(fp_line
			(start 0.508 -0.9398)
			(end -0.508 -0.9398)
			(stroke
				(width 0.1524)
				(type default)
			)
			(layer "F.SilkS")
		)
		(fp_line
			(start -0.508 -0.9398)
			(end -0.508 0.9398)
			(stroke
				(width 0.1524)
				(type default)
			)
			(layer "F.SilkS")
		)
		(fp_rect
			(start -0.508 0.9398)
			(end 0.508 -0.9398)
			(stroke
				(width 0)
				(type default)
			)
			(fill no)
			(layer "F.CrtYd")
		)
		(fp_rect
			(start -0.508 0.9398)
			(end 0.508 -0.9398)
			(stroke
				(width 0)
				(type default)
			)
			(fill no)
			(layer "F.Fab")
		)
		(pad "1" smd custom
			(at 0 -0.4445 180)
			(size 0.1397 0.1397)
			(layers "F.Cu" "F.Mask" "F.Paste")
			(net "SW_HDD_R28")
			(options
				(clearance outline)
				(anchor circle)
			)
			(primitives
				(gr_poly
					(pts
						(arc
							(start -0.1778 -0.2794)
							(mid -0.249642 -0.249642)
							(end -0.2794 -0.1778)
						)
						(arc
							(start -0.2794 0.1778)
							(mid -0.249642 0.249642)
							(end -0.1778 0.2794)
						)
						(arc
							(start 0.1778 0.2794)
							(mid 0.249642 0.249642)
							(end 0.2794 0.1778)
						)
						(arc
							(start 0.2794 -0.1778)
							(mid 0.249642 -0.249642)
							(end 0.1778 -0.2794)
						)
					)
					(width 0)
					(fill yes)
				)
			)
		)
		(pad "2" smd custom
			(at 0 0.4445 180)
			(size 0.1397 0.1397)
			(layers "F.Cu" "F.Mask" "F.Paste")
			(net "SW_HDD_N28")
			(options
				(clearance outline)
				(anchor circle)
			)
			(primitives
				(gr_poly
					(pts
						(arc
							(start -0.1778 -0.2794)
							(mid -0.249642 -0.249642)
							(end -0.2794 -0.1778)
						)
						(arc
							(start -0.2794 0.1778)
							(mid -0.249642 0.249642)
							(end -0.1778 0.2794)
						)
						(arc
							(start 0.1778 0.2794)
							(mid 0.249642 0.249642)
							(end 0.2794 0.1778)
						)
						(arc
							(start 0.2794 -0.1778)
							(mid 0.249642 -0.249642)
							(end 0.1778 -0.2794)
						)
					)
					(width 0)
					(fill yes)
				)
			)
		)
	)
	(footprint ""
		(layer "F.Cu")
		(at 181.6862 -42.291)
		(property "Reference" "C412"
			(at 0 0 0)
			(layer "F.SilkS")
			(hide yes)
			(effects
				(font
					(size 1.27 1.27)
				)
			)
		)
		(property "Value" "SC4D7U25V5KX-1-GP"
			(at -0.0762 -6.1214 0)
			(unlocked yes)
			(layer "F.Fab")
			(hide yes)
			(effects
				(font
					(size 1.016 1.016)
					(thickness 0.1524)
				)
			)
		)
		(property "Device Type" "C805H58"
			(at -0.0762 -8.1534 0)
			(unlocked yes)
			(layer "F.Fab")
			(hide yes)
			(effects
				(font
					(size 1.016 1.016)
					(thickness 0.1524)
				)
			)
		)
		(duplicate_pad_numbers_are_jumpers no)
		(fp_line
			(start 0.635 0)
			(end -0.635 0)
			(stroke
				(width 0.508)
				(type default)
			)
			(layer "F.SilkS")
		)
		(fp_rect
			(start -0.9652 1.778)
			(end 0.9652 -1.778)
			(stroke
				(width 0)
				(type default)
			)
			(fill no)
			(layer "F.CrtYd")
		)
		(fp_poly
			(pts
				(xy -0.9652 -1.778) (xy 0.9652 -1.778) (xy 0.9652 1.778) (xy -0.9652 1.778)
			)
			(stroke
				(width 0)
				(type default)
			)
			(fill no)
			(layer "F.Fab")
		)
		(pad "1" smd rect
			(at 0 -0.9652)
			(size 1.397 1.143)
			(layers "F.Cu" "F.Mask" "F.Paste")
			(net "P12V_HDD29")
		)
		(pad "2" smd rect
			(at 0 0.9652)
			(size 1.397 1.143)
			(layers "F.Cu" "F.Mask" "F.Paste")
			(net "GND")
		)
	)
)
